(kicad_pcb
	(version 20260206)
	(generator "pcbnew")
	(generator_version "10.0")
	(general
		(thickness 1.6)
		(legacy_teardrops no)
	)
	(paper "A4")
	(title_block
		(title "03242023_DA0F0TMBIJ0_F0T_Motherboard_J_brd_V01_OCP.brd")
		(comment 1 "Grand Teton / footprints 2872-2873 of 6105")
	)
	(layers
		(0 "F.Cu" signal "TOP")
		(4 "In1.Cu" signal "GND")
		(6 "In2.Cu" signal "IN1")
		(8 "In3.Cu" signal "GND1")
		(10 "In4.Cu" signal "IN2")
		(12 "In5.Cu" signal "GND2")
		(14 "In6.Cu" signal "IN3")
		(16 "In7.Cu" signal "GND3")
		(18 "In8.Cu" signal "VCC")
		(20 "In9.Cu" signal "VCC1")
		(22 "In10.Cu" signal "GND4")
		(24 "In11.Cu" signal "IN4")
		(26 "In12.Cu" signal "GND5")
		(28 "In13.Cu" signal "IN5")
		(30 "In14.Cu" signal "GND6")
		(32 "In15.Cu" signal "IN6")
		(34 "In16.Cu" signal "GND7")
		(2 "B.Cu" signal "BOTTOM")
		(9 "F.Adhes" user "F.Adhesive")
		(11 "B.Adhes" user "B.Adhesive")
		(13 "F.Paste" user "Package Geometry/Pastemask Top")
		(15 "B.Paste" user "Package Geometry/Pastemask Bottom")
		(5 "F.SilkS" user "Ref Des/Silkscreen Top")
		(7 "B.SilkS" user "Ref Des/Silkscreen Bottom")
		(1 "F.Mask" user "Board Geometry/Soldermask Top")
		(3 "B.Mask" user "Board Geometry/Soldermask Bottom")
		(17 "Dwgs.User" user "User.Drawings")
		(19 "Cmts.User" user "User.Comments")
		(21 "Eco1.User" user "User.Eco1")
		(23 "Eco2.User" user "User.Eco2")
		(25 "Edge.Cuts" user "Board Geometry/Outline")
		(27 "Margin" user)
		(31 "F.CrtYd" user "Package Geometry/Place Bound Top")
		(29 "B.CrtYd" user "Package Geometry/Place Bound Bottom")
		(35 "F.Fab" user "Ref Des/Assembly Top")
		(33 "B.Fab" user "Ref Des/Assembly Bottom")
	)
	(footprint ""
		(layer "F.Cu")
		(at 384.458972 -354.434902)
		(property "Reference" "H44"
			(at -3.03276 -5.138928 0)
			(unlocked yes)
			(layer "F.SilkS")
			(effects
				(font
					(size 0.7874 0.5842)
					(thickness 0.1524)
				)
				(justify left)
			)
		)
		(property "Value" ""
			(at 0 0 0)
			(layer "F.Fab")
			(effects
				(font
					(size 1.27 1.27)
				)
			)
		)
		(duplicate_pad_numbers_are_jumpers no)
		(pad "1" thru_hole circle
			(at 0 0)
			(size 8.001 8.001)
			(drill 3.2004)
			(layers "*.Cu" "*.Mask")
			(remove_unused_layers no)
			(net "GND")
			(clearance -2.1463)
			(padstack
				(mode front_inner_back)
				(layer "Inner"
					(shape circle)
					(size 5.0038 5.0038)
					(clearance -0.6477)
				)
				(layer "B.Cu"
					(shape circle)
					(size 8.001 8.001)
					(clearance -2.1463)
				)
			)
		)
	)
	(footprint ""
		(layer "F.Cu")
		(at 31.503366 -48.385476)
		(property "Reference" "ME29"
			(at 0 0 0)
			(layer "F.SilkS")
			(hide yes)
			(effects
				(font
					(size 1.27 1.27)
				)
			)
		)
		(property "Value" ""
			(at 0 0 0)
			(layer "F.Fab")
			(effects
				(font
					(size 1.27 1.27)
				)
			)
		)
		(duplicate_pad_numbers_are_jumpers no)
		(fp_line
			(start 0 -4.99999)
			(end 0 -3.47599)
			(stroke
				(width 0.1524)
				(type default)
			)
			(layer "F.SilkS")
		)
		(fp_line
			(start 0 -0.524002)
			(end 0 0.999998)
			(stroke
				(width 0.1524)
				(type default)
			)
			(layer "F.SilkS")
		)
		(fp_line
			(start 0 0.999998)
			(end 1.524 0.999998)
			(stroke
				(width 0.1524)
				(type default)
			)
			(layer "F.SilkS")
		)
		(fp_line
			(start 1.524 -4.99999)
			(end 0 -4.99999)
			(stroke
				(width 0.1524)
				(type default)
			)
			(layer "F.SilkS")
		)
		(fp_line
			(start 15.475966 0.999998)
			(end 16.999966 0.999998)
			(stroke
				(width 0.1524)
				(type default)
			)
			(layer "F.SilkS")
		)
		(fp_line
			(start 16.999966 -4.99999)
			(end 15.475966 -4.99999)
			(stroke
				(width 0.1524)
				(type default)
			)
			(layer "F.SilkS")
		)
		(fp_line
			(start 16.999966 -3.47599)
			(end 16.999966 -4.99999)
			(stroke
				(width 0.1524)
				(type default)
			)
			(layer "F.SilkS")
		)
		(fp_line
			(start 16.999966 0.999998)
			(end 16.999966 -0.524002)
			(stroke
				(width 0.1524)
				(type default)
			)
			(layer "F.SilkS")
		)
		(fp_text user "S/N"
			(at 0.1016 -3.54965 0)
			(unlocked yes)
			(layer "F.SilkS")
			(effects
				(font
					(size 1.905 1.4224)
					(thickness 0.1524)
				)
				(justify left)
			)
		)
	)
)
